(kicad_pcb
	(version 20260206)
	(generator "pcbnew")
	(generator_version "10.0")
	(general
		(thickness 1.6)
		(legacy_teardrops no)
	)
	(paper "A4")
	(title_block
		(title "baseboard — 13948-1b.1110WZS1818.brd")
		(comment 1 "Honey Badger (Wiwynn) / footprints 1556-1562 of 2523")
	)
	(layers
		(0 "F.Cu" signal "TOP")
		(4 "In1.Cu" signal "L2GND")
		(6 "In2.Cu" signal "L3")
		(8 "In3.Cu" signal "L4VCC")
		(10 "In4.Cu" signal "L5VCC")
		(12 "In5.Cu" signal "L6")
		(14 "In6.Cu" signal "L7GND")
		(2 "B.Cu" signal "BOTTOM")
		(9 "F.Adhes" user "F.Adhesive")
		(11 "B.Adhes" user "B.Adhesive")
		(13 "F.Paste" user "Package Geometry/Pastemask Top")
		(15 "B.Paste" user "Package Geometry/Pastemask Bottom")
		(5 "F.SilkS" user "Ref Des/Silkscreen Top")
		(7 "B.SilkS" user "Ref Des/Silkscreen Bottom")
		(1 "F.Mask" user "Board Geometry/Soldermask Top")
		(3 "B.Mask" user "Board Geometry/Soldermask Bottom")
		(17 "Dwgs.User" user "User.Drawings")
		(19 "Cmts.User" user "User.Comments")
		(21 "Eco1.User" user "User.Eco1")
		(23 "Eco2.User" user "User.Eco2")
		(25 "Edge.Cuts" user "Board Geometry/Outline")
		(27 "Margin" user)
		(31 "F.CrtYd" user "Package Geometry/Place Bound Top")
		(29 "B.CrtYd" user "Package Geometry/Place Bound Bottom")
		(35 "F.Fab" user "Ref Des/Assembly Top")
		(33 "B.Fab" user "Ref Des/Assembly Bottom")
	)
	(footprint ""
		(layer "F.Cu")
		(at 42.926 -169.291 90)
		(property "Reference" "C316"
			(at 0 0 90)
			(layer "F.SilkS")
			(hide yes)
			(effects
				(font
					(size 1.27 1.27)
				)
			)
		)
		(property "Value" "SC1U16V3KX-5GP"
			(at 0 -2.8194 90)
			(unlocked yes)
			(layer "F.Fab")
			(hide yes)
			(effects
				(font
					(size 1.016 1.016)
					(thickness 0.1524)
				)
			)
		)
		(property "Device Type" "C603H36"
			(at 0 -4.3434 90)
			(unlocked yes)
			(layer "F.Fab")
			(hide yes)
			(effects
				(font
					(size 1.016 1.016)
					(thickness 0.1524)
				)
			)
		)
		(duplicate_pad_numbers_are_jumpers no)
		(fp_line
			(start 0.508 0)
			(end -0.508 0)
			(stroke
				(width 0.2032)
				(type default)
			)
			(layer "F.SilkS")
		)
		(fp_rect
			(start -0.5842 1.3335)
			(end 0.5842 -1.3335)
			(stroke
				(width 0)
				(type default)
			)
			(fill no)
			(layer "F.CrtYd")
		)
		(fp_rect
			(start -0.5842 1.3335)
			(end 0.5842 -1.3335)
			(stroke
				(width 0)
				(type default)
			)
			(fill no)
			(layer "F.Fab")
		)
		(pad "1" smd custom
			(at 0 -0.762 90)
			(size 0.2159 0.2159)
			(layers "F.Cu" "F.Mask" "F.Paste")
			(net "FP_PWR_BTN_N")
			(options
				(clearance outline)
				(anchor circle)
			)
			(primitives
				(gr_poly
					(pts
						(arc
							(start -0.3302 -0.4318)
							(mid -0.402042 -0.402042)
							(end -0.4318 -0.3302)
						)
						(arc
							(start -0.4318 0.3302)
							(mid -0.402042 0.402042)
							(end -0.3302 0.4318)
						)
						(arc
							(start 0.3302 0.4318)
							(mid 0.402042 0.402042)
							(end 0.4318 0.3302)
						)
						(arc
							(start 0.4318 -0.3302)
							(mid 0.402042 -0.402042)
							(end 0.3302 -0.4318)
						)
					)
					(width 0)
					(fill yes)
				)
			)
		)
		(pad "2" smd custom
			(at 0 0.762 90)
			(size 0.2159 0.2159)
			(layers "F.Cu" "F.Mask" "F.Paste")
			(net "GND")
			(options
				(clearance outline)
				(anchor circle)
			)
			(primitives
				(gr_poly
					(pts
						(arc
							(start -0.3302 -0.4318)
							(mid -0.402042 -0.402042)
							(end -0.4318 -0.3302)
						)
						(arc
							(start -0.4318 0.3302)
							(mid -0.402042 0.402042)
							(end -0.3302 0.4318)
						)
						(arc
							(start 0.3302 0.4318)
							(mid 0.402042 0.402042)
							(end 0.4318 0.3302)
						)
						(arc
							(start 0.4318 -0.3302)
							(mid 0.402042 -0.402042)
							(end 0.3302 -0.4318)
						)
					)
					(width 0)
					(fill yes)
				)
			)
		)
	)
	(footprint ""
		(layer "F.Cu")
		(at 255.847596 -52.597812 90)
		(property "Reference" "SU61"
			(at 0 0 90)
			(layer "F.SilkS")
			(hide yes)
			(effects
				(font
					(size 1.27 1.27)
				)
			)
		)
		(property "Value" "AT24C64D-SSHM-T-GP"
			(at -3.707384 -1.5367 90)
			(unlocked yes)
			(layer "F.Fab")
			(hide yes)
			(effects
				(font
					(size 1.016 1.016)
					(thickness 0.1524)
				)
			)
		)
		(property "Device Type" "SOIC8H69"
			(at -3.707384 -3.0607 90)
			(unlocked yes)
			(layer "F.Fab")
			(hide yes)
			(effects
				(font
					(size 1.016 1.016)
					(thickness 0.1524)
				)
			)
		)
		(duplicate_pad_numbers_are_jumpers no)
		(fp_line
			(start 2.1336 -1.4224)
			(end -2.7432 -1.4224)
			(stroke
				(width 0.1524)
				(type default)
			)
			(layer "F.SilkS")
		)
		(fp_line
			(start -2.7432 -1.4224)
			(end -2.7432 1.4224)
			(stroke
				(width 0.1524)
				(type default)
			)
			(layer "F.SilkS")
		)
		(fp_line
			(start -2.7178 -0.508)
			(end -2.1844 -0.0508)
			(stroke
				(width 0.1524)
				(type default)
			)
			(layer "F.SilkS")
		)
		(fp_line
			(start -2.1844 -0.0508)
			(end -2.7178 0.508)
			(stroke
				(width 0.1524)
				(type default)
			)
			(layer "F.SilkS")
		)
		(fp_line
			(start 2.1336 1.4224)
			(end 2.1336 -1.4224)
			(stroke
				(width 0.1524)
				(type default)
			)
			(layer "F.SilkS")
		)
		(fp_line
			(start -2.7432 1.4224)
			(end 2.1336 1.4224)
			(stroke
				(width 0.1524)
				(type default)
			)
			(layer "F.SilkS")
		)
		(fp_line
			(start -2.7432 1.4224)
			(end -2.6416 1.4224)
			(stroke
				(width 0.1524)
				(type default)
			)
			(layer "F.SilkS")
		)
		(fp_line
			(start -2.6289 3.4417)
			(end -2.6289 1.4732)
			(stroke
				(width 0.381)
				(type default)
			)
			(layer "F.SilkS")
		)
		(fp_poly
			(pts
				(xy -2.2098 -1.4224) (xy -2.2098 1.4224) (xy 2.2098 1.4224) (xy 2.2098 -1.4224)
			)
			(stroke
				(width 0)
				(type default)
			)
			(fill yes)
			(layer "F.SilkS")
		)
		(fp_rect
			(start -2.450084 2.999994)
			(end 2.450084 -2.999994)
			(stroke
				(width 0)
				(type default)
			)
			(fill no)
			(layer "F.CrtYd")
		)
		(fp_poly
			(pts
				(xy -2.8194 3.6322) (xy -2.8194 -3.6322) (xy 2.8194 -3.6322) (xy 2.8194 1.18364) (xy 2.450084 1.18364)
				(xy 2.450084 -2.999994) (xy -2.450084 -2.999994) (xy -2.450084 2.999994) (xy 2.450084 2.999994)
				(xy 2.450084 1.18618) (xy 2.8194 1.18618) (xy 2.8194 3.6322)
			)
			(stroke
				(width 0)
				(type default)
			)
			(fill no)
			(layer "F.CrtYd")
		)
		(fp_rect
			(start -2.8194 3.6322)
			(end 2.8194 -3.6322)
			(stroke
				(width 0)
				(type default)
			)
			(fill no)
			(layer "F.Fab")
		)
		(pad "1" smd rect
			(at -1.905 2.54 90)
			(size 0.635 1.651)
			(layers "F.Cu" "F.Mask" "F.Paste")
			(net "IOC_EEPROM_A0")
		)
		(pad "2" smd rect
			(at -0.635 2.54 90)
			(size 0.635 1.651)
			(layers "F.Cu" "F.Mask" "F.Paste")
			(net "IOC_EEPROM_A1")
		)
		(pad "3" smd rect
			(at 0.635 2.54 90)
			(size 0.635 1.651)
			(layers "F.Cu" "F.Mask" "F.Paste")
			(net "IOC_EEPROM_A2")
		)
		(pad "4" smd rect
			(at 1.905 2.54 90)
			(size 0.635 1.651)
			(layers "F.Cu" "F.Mask" "F.Paste")
			(net "GND")
		)
		(pad "5" smd rect
			(at 1.905 -2.54 90)
			(size 0.635 1.651)
			(layers "F.Cu" "F.Mask" "F.Paste")
			(net "IOC_EEPROM_SDA")
		)
		(pad "6" smd rect
			(at 0.635 -2.54 90)
			(size 0.635 1.651)
			(layers "F.Cu" "F.Mask" "F.Paste")
			(net "IOC_EEPROM_SCL")
		)
		(pad "7" smd rect
			(at -0.635 -2.54 90)
			(size 0.635 1.651)
			(layers "F.Cu" "F.Mask" "F.Paste")
			(net "IOC_EEPROM_WP")
		)
		(pad "8" smd rect
			(at -1.905 -2.54 90)
			(size 0.635 1.651)
			(layers "F.Cu" "F.Mask" "F.Paste")
			(net "P1V8_C")
		)
	)
	(footprint ""
		(layer "F.Cu")
		(at 342.904318 -156.416248 -90)
		(property "Reference" "TP169"
			(at 0 0 270)
			(layer "F.SilkS")
			(hide yes)
			(effects
				(font
					(size 1.27 1.27)
				)
			)
		)
		(property "Value" "TPAD28"
			(at 0.0127 -1.8034 270)
			(unlocked yes)
			(layer "F.Fab")
			(hide yes)
			(effects
				(font
					(size 1.016 1.016)
					(thickness 0.1524)
				)
			)
		)
		(property "Device Type" "TPAD28"
			(at 0.0127 -3.3274 270)
			(unlocked yes)
			(layer "F.Fab")
			(hide yes)
			(effects
				(font
					(size 1.016 1.016)
					(thickness 0.1524)
				)
			)
		)
		(duplicate_pad_numbers_are_jumpers no)
		(fp_poly
			(pts
				(arc
					(start 0 -0.3556)
					(mid 0 0.3556)
					(end 0 -0.3556)
				)
			)
			(stroke
				(width 0)
				(type default)
			)
			(fill no)
			(layer "F.CrtYd")
		)
		(fp_poly
			(pts
				(arc
					(start 0 -0.6096)
					(mid 0 0.6096)
					(end 0 -0.6096)
				)
			)
			(stroke
				(width 0)
				(type default)
			)
			(fill no)
			(layer "F.Fab")
		)
		(pad "1" smd circle
			(at 0 0 270)
			(size 0.7112 0.7112)
			(layers "F.Cu" "F.Mask" "F.Paste")
			(net "CRFILT")
		)
	)
	(footprint ""
		(layer "F.Cu")
		(at 140.95857 -93.9546)
		(property "Reference" "R596"
			(at 0 0 0)
			(layer "F.SilkS")
			(hide yes)
			(effects
				(font
					(size 1.27 1.27)
				)
			)
		)
		(property "Value" "0R2J-2-GP"
			(at 0.064008 -3.993896 0)
			(unlocked yes)
			(layer "F.Fab")
			(hide yes)
			(effects
				(font
					(size 1.016 1.016)
					(thickness 0.1524)
				)
			)
		)
		(property "Device Type" "R402H16"
			(at 0.064008 -5.517896 0)
			(unlocked yes)
			(layer "F.Fab")
			(hide yes)
			(effects
				(font
					(size 1.016 1.016)
					(thickness 0.1524)
				)
			)
		)
		(duplicate_pad_numbers_are_jumpers no)
		(fp_line
			(start -0.508 -0.9398)
			(end -0.508 0.9398)
			(stroke
				(width 0.1524)
				(type default)
			)
			(layer "F.SilkS")
		)
		(fp_line
			(start 0.508 -0.9398)
			(end -0.508 -0.9398)
			(stroke
				(width 0.1524)
				(type default)
			)
			(layer "F.SilkS")
		)
		(fp_rect
			(start -0.508 0.9398)
			(end 0.508 -0.9398)
			(stroke
				(width 0)
				(type default)
			)
			(fill no)
			(layer "F.CrtYd")
		)
		(fp_rect
			(start -0.508 0.9398)
			(end 0.508 -0.9398)
			(stroke
				(width 0)
				(type default)
			)
			(fill no)
			(layer "F.Fab")
		)
		(pad "1" smd custom
			(at 0 -0.4445)
			(size 0.1397 0.1397)
			(layers "F.Cu" "F.Mask" "F.Paste")
			(net "BMC_I2C_D_SCL")
			(options
				(clearance outline)
				(anchor circle)
			)
			(primitives
				(gr_poly
					(pts
						(arc
							(start -0.1778 -0.2794)
							(mid -0.249642 -0.249642)
							(end -0.2794 -0.1778)
						)
						(arc
							(start -0.2794 0.1778)
							(mid -0.249642 0.249642)
							(end -0.1778 0.2794)
						)
						(arc
							(start 0.1778 0.2794)
							(mid 0.249642 0.249642)
							(end 0.2794 0.1778)
						)
						(arc
							(start 0.2794 -0.1778)
							(mid 0.249642 -0.249642)
							(end 0.1778 -0.2794)
						)
					)
					(width 0)
					(fill yes)
				)
			)
		)
		(pad "2" smd custom
			(at 0 0.4445)
			(size 0.1397 0.1397)
			(layers "F.Cu" "F.Mask" "F.Paste")
			(net "TEMP_3_SCL")
			(options
				(clearance outline)
				(anchor circle)
			)
			(primitives
				(gr_poly
					(pts
						(arc
							(start -0.1778 -0.2794)
							(mid -0.249642 -0.249642)
							(end -0.2794 -0.1778)
						)
						(arc
							(start -0.2794 0.1778)
							(mid -0.249642 0.249642)
							(end -0.1778 0.2794)
						)
						(arc
							(start 0.1778 0.2794)
							(mid 0.249642 0.249642)
							(end 0.2794 0.1778)
						)
						(arc
							(start 0.2794 -0.1778)
							(mid 0.249642 -0.249642)
							(end 0.1778 -0.2794)
						)
					)
					(width 0)
					(fill yes)
				)
			)
		)
	)
	(footprint ""
		(layer "F.Cu")
		(at 131.66471 -98.92284 180)
		(property "Reference" "SC1272"
			(at 0 0 180)
			(layer "F.SilkS")
			(hide yes)
			(effects
				(font
					(size 1.27 1.27)
				)
			)
		)
		(property "Value" "SCD01U10V1KX-GP"
			(at -2.8321 -1.7399 180)
			(unlocked yes)
			(layer "F.Fab")
			(hide yes)
			(effects
				(font
					(size 1.016 1.016)
					(thickness 0.1524)
				)
			)
		)
		(property "Device Type" "C0201H13"
			(at -2.8321 -3.2639 180)
			(unlocked yes)
			(layer "F.Fab")
			(hide yes)
			(effects
				(font
					(size 1.016 1.016)
					(thickness 0.1524)
				)
			)
		)
		(duplicate_pad_numbers_are_jumpers no)
		(fp_rect
			(start -0.2794 0.6477)
			(end 0.2794 -0.6477)
			(stroke
				(width 0)
				(type default)
			)
			(fill no)
			(layer "F.CrtYd")
		)
		(fp_rect
			(start -0.2794 0.6477)
			(end 0.2794 -0.6477)
			(stroke
				(width 0)
				(type default)
			)
			(fill no)
			(layer "F.Fab")
		)
		(pad "1" smd custom
			(at 0 -0.2794 180)
			(size 0.0762 0.0762)
			(layers "F.Cu" "F.Mask" "F.Paste")
			(net "3X24_SAS_TX23_P")
			(options
				(clearance outline)
				(anchor circle)
			)
			(primitives
				(gr_poly
					(pts
						(arc
							(start 0.1524 -0.127)
							(mid 0.137521 -0.162921)
							(end 0.1016 -0.1778)
						)
						(arc
							(start -0.1016 -0.1778)
							(mid -0.137521 -0.162921)
							(end -0.1524 -0.127)
						)
						(arc
							(start -0.1524 0.127)
							(mid -0.137521 0.162921)
							(end -0.1016 0.1778)
						)
						(arc
							(start 0.1016 0.1778)
							(mid 0.137521 0.162921)
							(end 0.1524 0.127)
						)
					)
					(width 0)
					(fill yes)
				)
			)
		)
		(pad "2" smd custom
			(at 0 0.2794 180)
			(size 0.0762 0.0762)
			(layers "F.Cu" "F.Mask" "F.Paste")
			(net "SAS_EXP_GF_TX_DP3")
			(options
				(clearance outline)
				(anchor circle)
			)
			(primitives
				(gr_poly
					(pts
						(arc
							(start 0.1524 -0.127)
							(mid 0.137521 -0.162921)
							(end 0.1016 -0.1778)
						)
						(arc
							(start -0.1016 -0.1778)
							(mid -0.137521 -0.162921)
							(end -0.1524 -0.127)
						)
						(arc
							(start -0.1524 0.127)
							(mid -0.137521 0.162921)
							(end -0.1016 0.1778)
						)
						(arc
							(start 0.1016 0.1778)
							(mid 0.137521 0.162921)
							(end 0.1524 0.127)
						)
					)
					(width 0)
					(fill yes)
				)
			)
		)
	)
	(footprint ""
		(layer "F.Cu")
		(at 197.938136 -167.267128 90)
		(property "Reference" "Q12"
			(at 0 0 90)
			(layer "F.SilkS")
			(hide yes)
			(effects
				(font
					(size 1.27 1.27)
				)
			)
		)
		(property "Value" "2N7002A-7-GP"
			(at 0.127 -8.9662 90)
			(unlocked yes)
			(layer "F.Fab")
			(hide yes)
			(effects
				(font
					(size 1.016 1.016)
					(thickness 0.1524)
				)
			)
		)
		(property "Device Type" "SOT23DGS2D4H48"
			(at 0.127 -10.4902 90)
			(unlocked yes)
			(layer "F.Fab")
			(hide yes)
			(effects
				(font
					(size 1.016 1.016)
					(thickness 0.1524)
				)
			)
		)
		(duplicate_pad_numbers_are_jumpers no)
		(fp_line
			(start 1.651 -1.778)
			(end -1.651 -1.778)
			(stroke
				(width 0.1524)
				(type default)
			)
			(layer "F.SilkS")
		)
		(fp_line
			(start -1.651 -1.778)
			(end -1.651 1.778)
			(stroke
				(width 0.1524)
				(type default)
			)
			(layer "F.SilkS")
		)
		(fp_line
			(start 1.651 1.778)
			(end 1.651 -1.778)
			(stroke
				(width 0.1524)
				(type default)
			)
			(layer "F.SilkS")
		)
		(fp_line
			(start -1.651 1.778)
			(end 1.651 1.778)
			(stroke
				(width 0.1524)
				(type default)
			)
			(layer "F.SilkS")
		)
		(fp_poly
			(pts
				(xy -1.778 1.8796) (xy -1.778 -1.8796) (xy 1.778 -1.8796) (xy 1.778 1.8796)
			)
			(stroke
				(width 0)
				(type default)
			)
			(fill no)
			(layer "F.CrtYd")
		)
		(fp_poly
			(pts
				(xy -1.778 1.8796) (xy -1.778 -1.8796) (xy 1.778 -1.8796) (xy 1.778 1.8796)
			)
			(stroke
				(width 0)
				(type default)
			)
			(fill no)
			(layer "F.Fab")
		)
		(pad "D" smd custom
			(at 0 -0.9525 90)
			(size 0.1905 0.1905)
			(layers "F.Cu" "F.Mask" "F.Paste")
			(net "P3V3_STBY_R1")
			(options
				(clearance outline)
				(anchor circle)
			)
			(primitives
				(gr_poly
					(pts
						(arc
							(start -0.1778 0.5715)
							(mid -0.321484 0.511984)
							(end -0.381 0.3683)
						)
						(arc
							(start -0.381 -0.3683)
							(mid -0.321484 -0.511984)
							(end -0.1778 -0.5715)
						)
						(arc
							(start 0.1778 -0.5715)
							(mid 0.321484 -0.511984)
							(end 0.381 -0.3683)
						)
						(arc
							(start 0.381 0.3683)
							(mid 0.321484 0.511984)
							(end 0.1778 0.5715)
						)
					)
					(width 0)
					(fill yes)
				)
			)
		)
		(pad "G" smd custom
			(at -0.98425 0.9525 90)
			(size 0.1905 0.1905)
			(layers "F.Cu" "F.Mask" "F.Paste")
			(net "P3V3_B")
			(options
				(clearance outline)
				(anchor circle)
			)
			(primitives
				(gr_poly
					(pts
						(arc
							(start -0.1778 0.5715)
							(mid -0.321484 0.511984)
							(end -0.381 0.3683)
						)
						(arc
							(start -0.381 -0.3683)
							(mid -0.321484 -0.511984)
							(end -0.1778 -0.5715)
						)
						(arc
							(start 0.1778 -0.5715)
							(mid 0.321484 -0.511984)
							(end 0.381 -0.3683)
						)
						(arc
							(start 0.381 0.3683)
							(mid 0.321484 0.511984)
							(end 0.1778 0.5715)
						)
					)
					(width 0)
					(fill yes)
				)
			)
		)
		(pad "S" smd custom
			(at 0.98425 0.9525 90)
			(size 0.1905 0.1905)
			(layers "F.Cu" "F.Mask" "F.Paste")
			(net "GND")
			(options
				(clearance outline)
				(anchor circle)
			)
			(primitives
				(gr_poly
					(pts
						(arc
							(start -0.1778 0.5715)
							(mid -0.321484 0.511984)
							(end -0.381 0.3683)
						)
						(arc
							(start -0.381 -0.3683)
							(mid -0.321484 -0.511984)
							(end -0.1778 -0.5715)
						)
						(arc
							(start 0.1778 -0.5715)
							(mid 0.321484 -0.511984)
							(end 0.381 -0.3683)
						)
						(arc
							(start 0.381 0.3683)
							(mid 0.321484 0.511984)
							(end 0.1778 0.5715)
						)
					)
					(width 0)
					(fill yes)
				)
			)
		)
	)
	(footprint ""
		(layer "F.Cu")
		(at 179.324 -18.415 90)
		(property "Reference" "R201"
			(at 0 0 90)
			(layer "F.SilkS")
			(hide yes)
			(effects
				(font
					(size 1.27 1.27)
				)
			)
		)
		(property "Value" "49D9R2D-GP"
			(at 0.064008 -3.993896 90)
			(unlocked yes)
			(layer "F.Fab")
			(hide yes)
			(effects
				(font
					(size 1.016 1.016)
					(thickness 0.1524)
				)
			)
		)
		(property "Device Type" "R402H16"
			(at 0.064008 -5.517896 90)
			(unlocked yes)
			(layer "F.Fab")
			(hide yes)
			(effects
				(font
					(size 1.016 1.016)
					(thickness 0.1524)
				)
			)
		)
		(duplicate_pad_numbers_are_jumpers no)
		(fp_line
			(start 0.508 -0.9398)
			(end -0.508 -0.9398)
			(stroke
				(width 0.1524)
				(type default)
			)
			(layer "F.SilkS")
		)
		(fp_line
			(start -0.508 -0.9398)
			(end -0.508 0.9398)
			(stroke
				(width 0.1524)
				(type default)
			)
			(layer "F.SilkS")
		)
		(fp_rect
			(start -0.508 0.9398)
			(end 0.508 -0.9398)
			(stroke
				(width 0)
				(type default)
			)
			(fill no)
			(layer "F.CrtYd")
		)
		(fp_rect
			(start -0.508 0.9398)
			(end 0.508 -0.9398)
			(stroke
				(width 0)
				(type default)
			)
			(fill no)
			(layer "F.Fab")
		)
		(pad "1" smd custom
			(at 0 -0.4445 90)
			(size 0.1397 0.1397)
			(layers "F.Cu" "F.Mask" "F.Paste")
			(net "TEMP_SENSOR_DXP_R")
			(options
				(clearance outline)
				(anchor circle)
			)
			(primitives
				(gr_poly
					(pts
						(arc
							(start -0.1778 -0.2794)
							(mid -0.249642 -0.249642)
							(end -0.2794 -0.1778)
						)
						(arc
							(start -0.2794 0.1778)
							(mid -0.249642 0.249642)
							(end -0.1778 0.2794)
						)
						(arc
							(start 0.1778 0.2794)
							(mid 0.249642 0.249642)
							(end 0.2794 0.1778)
						)
						(arc
							(start 0.2794 -0.1778)
							(mid 0.249642 -0.249642)
							(end 0.1778 -0.2794)
						)
					)
					(width 0)
					(fill yes)
				)
			)
		)
		(pad "2" smd custom
			(at 0 0.4445 90)
			(size 0.1397 0.1397)
			(layers "F.Cu" "F.Mask" "F.Paste")
			(net "TEMP_SENSOR_DXP")
			(options
				(clearance outline)
				(anchor circle)
			)
			(primitives
				(gr_poly
					(pts
						(arc
							(start -0.1778 -0.2794)
							(mid -0.249642 -0.249642)
							(end -0.2794 -0.1778)
						)
						(arc
							(start -0.2794 0.1778)
							(mid -0.249642 0.249642)
							(end -0.1778 0.2794)
						)
						(arc
							(start 0.1778 0.2794)
							(mid 0.249642 0.249642)
							(end 0.2794 0.1778)
						)
						(arc
							(start 0.2794 -0.1778)
							(mid 0.249642 -0.249642)
							(end 0.1778 -0.2794)
						)
					)
					(width 0)
					(fill yes)
				)
			)
		)
	)
)
